(kicad_pcb
	(version 20260206)
	(generator "pcbnew")
	(generator_version "10.0")
	(general
		(thickness 1.6)
		(legacy_teardrops no)
	)
	(paper "A4")
	(title_block
		(title "Wiwynn_Tioga_Pass_MB.brd")
		(comment 1 "Tioga Pass / footprint 2254 of 4770 (U5D1), pads 2737-2826 of 3647")
	)
	(layers
		(0 "F.Cu" signal "TOP")
		(4 "In1.Cu" signal "L2GND")
		(6 "In2.Cu" signal "L3")
		(8 "In3.Cu" signal "L4GND")
		(10 "In4.Cu" signal "L5")
		(12 "In5.Cu" signal "L6GND")
		(14 "In6.Cu" signal "L7VCC")
		(16 "In7.Cu" signal "L8VCC")
		(18 "In8.Cu" signal "L9GND")
		(20 "In9.Cu" signal "L10")
		(22 "In10.Cu" signal "L11GND")
		(24 "In11.Cu" signal "L12")
		(26 "In12.Cu" signal "L13GND")
		(2 "B.Cu" signal "BOTTOM")
		(9 "F.Adhes" user "F.Adhesive")
		(11 "B.Adhes" user "B.Adhesive")
		(13 "F.Paste" user "Package Geometry/Pastemask Top")
		(15 "B.Paste" user "Package Geometry/Pastemask Bottom")
		(5 "F.SilkS" user "Ref Des/Silkscreen Top")
		(7 "B.SilkS" user "Ref Des/Silkscreen Bottom")
		(1 "F.Mask" user "Board Geometry/Soldermask Top")
		(3 "B.Mask" user "Board Geometry/Soldermask Bottom")
		(17 "Dwgs.User" user "User.Drawings")
		(19 "Cmts.User" user "User.Comments")
		(21 "Eco1.User" user "User.Eco1")
		(23 "Eco2.User" user "User.Eco2")
		(25 "Edge.Cuts" user "Board Geometry/Outline")
		(27 "Margin" user)
		(31 "F.CrtYd" user "Package Geometry/Place Bound Top")
		(29 "B.CrtYd" user "Package Geometry/Place Bound Bottom")
		(35 "F.Fab" user "Ref Des/Assembly Top")
		(33 "B.Fab" user "Ref Des/Assembly Bottom")
	)
	(footprint ""
		(layer "F.Cu")
		(at 270.000222 -76.550012 180)
		(property "Reference" "U5D1"
			(at 19.124422 31.601918 0)
			(unlocked yes)
			(layer "F.SilkS")
			(effects
				(font
					(size 0.7874 0.5842)
					(thickness 0.1524)
				)
			)
		)
		(property "Value" ""
			(at 0 0 180)
			(layer "F.Fab")
			(effects
				(font
					(size 1.27 1.27)
				)
			)
		)
		(duplicate_pad_numbers_are_jumpers no)
		(pad "DY11" smd circle
			(at -28.665424 23.931626)
			(size 0.4318 0.4318)
			(layers "F.Cu" "F.Mask" "F.Paste")
			(net "P3E_CPU0_PE3_OCP_TXN<3>")
		)
		(pad "DY13" smd circle
			(at -26.948384 23.931626)
			(size 0.4318 0.4318)
			(layers "F.Cu" "F.Mask" "F.Paste")
			(net "P3E_CPU0_PE1_PCH_RXP<13>")
		)
		(pad "DY15" smd circle
			(at -25.231598 23.931626)
			(size 0.4318 0.4318)
			(layers "F.Cu" "F.Mask" "F.Paste")
			(net "P3E_CPU0_PE1_PCH_RXN<14>")
		)
		(pad "DY17" smd circle
			(at -23.514558 23.931626)
			(size 0.4318 0.4318)
			(layers "F.Cu" "F.Mask" "F.Paste")
			(net "P3E_CPU0_PE3_OCP_RXP<0>")
		)
		(pad "DY19" smd circle
			(at -21.797518 23.931626)
			(size 0.4318 0.4318)
			(layers "F.Cu" "F.Mask" "F.Paste")
			(net "GND")
		)
		(pad "DY21" smd circle
			(at -20.080478 23.931626)
			(size 0.4318 0.4318)
			(layers "F.Cu" "F.Mask" "F.Paste")
			(net "M_D_DQ<58>")
		)
		(pad "DY23" smd circle
			(at -18.363438 23.931626)
			(size 0.4318 0.4318)
			(layers "F.Cu" "F.Mask" "F.Paste")
			(net "GND")
		)
		(pad "DY25" smd circle
			(at -16.646398 23.931626)
			(size 0.4318 0.4318)
			(layers "F.Cu" "F.Mask" "F.Paste")
			(net "M_E_DQ<54>")
		)
		(pad "DY27" smd circle
			(at -14.929612 23.931626)
			(size 0.4318 0.4318)
			(layers "F.Cu" "F.Mask" "F.Paste")
			(net "M_E_DQ<52>")
		)
		(pad "DY29" smd circle
			(at -13.212572 23.931626)
			(size 0.4318 0.4318)
			(layers "F.Cu" "F.Mask" "F.Paste")
			(net "GND")
		)
		(pad "DY31" smd circle
			(at -11.495532 23.931626)
			(size 0.4318 0.4318)
			(layers "F.Cu" "F.Mask" "F.Paste")
			(net "M_E_DQ<46>")
		)
		(pad "DY33" smd circle
			(at -9.778492 23.931626)
			(size 0.4318 0.4318)
			(layers "F.Cu" "F.Mask" "F.Paste")
			(net "M_E_DQ<44>")
		)
		(pad "DY35" smd circle
			(at -8.061452 23.931626)
			(size 0.4318 0.4318)
			(layers "F.Cu" "F.Mask" "F.Paste")
			(net "GND")
		)
		(pad "DY37" smd circle
			(at -6.344412 23.931626)
			(size 0.4318 0.4318)
			(layers "F.Cu" "F.Mask" "F.Paste")
			(net "M_D_DQ<38>")
		)
		(pad "DY39" smd circle
			(at -4.627626 23.931626)
			(size 0.4318 0.4318)
			(layers "F.Cu" "F.Mask" "F.Paste")
			(net "M_D_DQ<36>")
		)
		(pad "DY41" smd circle
			(at -2.910586 23.931626)
			(size 0.4318 0.4318)
			(layers "F.Cu" "F.Mask" "F.Paste")
			(net "GND")
		)
		(pad "DY45" smd circle
			(at 2.052066 22.131274)
			(size 0.4318 0.4318)
			(layers "F.Cu" "F.Mask" "F.Paste")
			(net "GND")
		)
		(pad "DY47" smd circle
			(at 3.769106 22.131274)
			(size 0.4318 0.4318)
			(layers "F.Cu" "F.Mask" "F.Paste")
			(net "GND")
		)
		(pad "DY49" smd circle
			(at 5.485892 22.131274)
			(size 0.4318 0.4318)
			(layers "F.Cu" "F.Mask" "F.Paste")
			(net "GND")
		)
		(pad "DY51" smd circle
			(at 7.202932 22.131274)
			(size 0.4318 0.4318)
			(layers "F.Cu" "F.Mask" "F.Paste")
			(net "GND")
		)
		(pad "DY53" smd circle
			(at 8.919972 22.131274)
			(size 0.4318 0.4318)
			(layers "F.Cu" "F.Mask" "F.Paste")
			(net "GND")
		)
		(pad "DY55" smd circle
			(at 10.637012 22.131274)
			(size 0.4318 0.4318)
			(layers "F.Cu" "F.Mask" "F.Paste")
			(net "GND")
		)
		(pad "DY57" smd circle
			(at 12.354052 22.131274)
			(size 0.4318 0.4318)
			(layers "F.Cu" "F.Mask" "F.Paste")
			(net "GND")
		)
		(pad "DY59" smd circle
			(at 14.071092 22.131274)
			(size 0.4318 0.4318)
			(layers "F.Cu" "F.Mask" "F.Paste")
			(net "GND")
		)
		(pad "DY61" smd circle
			(at 15.787878 22.131274)
			(size 0.4318 0.4318)
			(layers "F.Cu" "F.Mask" "F.Paste")
			(net "GND")
		)
		(pad "DY63" smd circle
			(at 17.504918 22.131274)
			(size 0.4318 0.4318)
			(layers "F.Cu" "F.Mask" "F.Paste")
			(net "GND")
		)
		(pad "DY65" smd circle
			(at 19.221958 22.131274)
			(size 0.4318 0.4318)
			(layers "F.Cu" "F.Mask" "F.Paste")
			(net "M_E_ECC<3>")
		)
		(pad "DY67" smd circle
			(at 20.938998 22.131274)
			(size 0.4318 0.4318)
			(layers "F.Cu" "F.Mask" "F.Paste")
			(net "M_E_DQS_DP<8>")
		)
		(pad "DY69" smd circle
			(at 22.656038 22.131274)
			(size 0.4318 0.4318)
			(layers "F.Cu" "F.Mask" "F.Paste")
			(net "M_E_ECC<0>")
		)
		(pad "DY71" smd circle
			(at 24.373078 22.131274)
			(size 0.4318 0.4318)
			(layers "F.Cu" "F.Mask" "F.Paste")
			(net "GND")
		)
		(pad "DY73" smd circle
			(at 26.090118 22.131274)
			(size 0.4318 0.4318)
			(layers "F.Cu" "F.Mask" "F.Paste")
			(net "M_E_DQS_DP<12>")
		)
		(pad "DY75" smd circle
			(at 27.806904 22.131274)
			(size 0.4318 0.4318)
			(layers "F.Cu" "F.Mask" "F.Paste")
			(net "GND")
		)
		(pad "DY77" smd circle
			(at 29.523944 22.131274)
			(size 0.4318 0.4318)
			(layers "F.Cu" "F.Mask" "F.Paste")
			(net "M_E_DQ<18>")
		)
		(pad "DY79" smd circle
			(at 31.240984 22.131274)
			(size 0.4318 0.4318)
			(layers "F.Cu" "F.Mask" "F.Paste")
			(net "M_E_DQS_DN<11>")
		)
		(pad "DY81" smd circle
			(at 32.958024 22.131274)
			(size 0.4318 0.4318)
			(layers "F.Cu" "F.Mask" "F.Paste")
			(net "M_E_DQ<20>")
		)
		(pad "DY83" smd circle
			(at 34.675064 22.131274)
			(size 0.4318 0.4318)
			(layers "F.Cu" "F.Mask" "F.Paste")
			(net "M_D_DQ<11>")
		)
		(pad "DY85" smd custom
			(at 36.392104 22.131274 225)
			(size 0.10795 0.10795)
			(layers "F.Cu" "F.Mask" "F.Paste")
			(net "GND")
			(options
				(clearance outline)
				(anchor circle)
			)
			(primitives
				(gr_poly
					(pts
						(arc
							(start 0.2159 -0.0381)
							(mid 0 -0.254)
							(end -0.2159 -0.0381)
						)
						(arc
							(start -0.2159 0.0381)
							(mid 0 0.254)
							(end 0.2159 0.0381)
						)
					)
					(width 0)
					(fill yes)
				)
			)
		)
		(pad "E2" smd custom
			(at -36.392104 -23.122128 45)
			(size 0.10795 0.10795)
			(layers "F.Cu" "F.Mask" "F.Paste")
			(net "TP_CPU0_RSVD_283")
			(options
				(clearance outline)
				(anchor circle)
			)
			(primitives
				(gr_poly
					(pts
						(arc
							(start 0.2159 -0.0381)
							(mid 0 -0.254)
							(end -0.2159 -0.0381)
						)
						(arc
							(start -0.2159 0.0381)
							(mid 0 0.254)
							(end 0.2159 0.0381)
						)
					)
					(width 0)
					(fill yes)
				)
			)
		)
		(pad "E4" smd custom
			(at -34.675064 -23.122128 45)
			(size 0.10795 0.10795)
			(layers "F.Cu" "F.Mask" "F.Paste")
			(net "TP_CPU0_RSVD_282")
			(options
				(clearance outline)
				(anchor circle)
			)
			(primitives
				(gr_poly
					(pts
						(arc
							(start 0.2159 -0.0381)
							(mid 0 -0.254)
							(end -0.2159 -0.0381)
						)
						(arc
							(start -0.2159 0.0381)
							(mid 0 0.254)
							(end 0.2159 0.0381)
						)
					)
					(width 0)
					(fill yes)
				)
			)
		)
		(pad "E6" smd circle
			(at -32.958024 -23.122128)
			(size 0.4318 0.4318)
			(layers "F.Cu" "F.Mask" "F.Paste")
			(net "GND")
		)
		(pad "E8" smd circle
			(at -31.240984 -23.122128)
			(size 0.4318 0.4318)
			(layers "F.Cu" "F.Mask" "F.Paste")
			(net "GND")
		)
		(pad "E10" smd circle
			(at -29.523944 -23.122128)
			(size 0.4318 0.4318)
			(layers "F.Cu" "F.Mask" "F.Paste")
			(net "UPI_CPU0_CPU1_P1P1_DP<11>")
		)
		(pad "E12" smd circle
			(at -27.806904 -23.122128)
			(size 0.4318 0.4318)
			(layers "F.Cu" "F.Mask" "F.Paste")
			(net "UPI_CPU0_CPU1_P1P1_DN<9>")
		)
		(pad "E14" smd circle
			(at -26.090118 -23.122128)
			(size 0.4318 0.4318)
			(layers "F.Cu" "F.Mask" "F.Paste")
			(net "UPI_CPU0_CPU1_P1P1_DP<7>")
		)
		(pad "E16" smd circle
			(at -24.373078 -23.122128)
			(size 0.4318 0.4318)
			(layers "F.Cu" "F.Mask" "F.Paste")
			(net "GND")
		)
		(pad "E18" smd custom
			(at -22.656038 -23.122128)
			(size 0.10795 0.10795)
			(layers "F.Cu" "F.Mask" "F.Paste")
			(net "GND")
			(options
				(clearance outline)
				(anchor circle)
			)
			(primitives
				(gr_poly
					(pts
						(arc
							(start 0.2159 -0.0381)
							(mid 0 -0.254)
							(end -0.2159 -0.0381)
						)
						(arc
							(start -0.2159 0.0381)
							(mid 0 0.254)
							(end 0.2159 0.0381)
						)
					)
					(width 0)
					(fill yes)
				)
			)
		)
		(pad "E20" smd custom
			(at -20.938998 -23.122128)
			(size 0.10795 0.10795)
			(layers "F.Cu" "F.Mask" "F.Paste")
			(net "GND")
			(options
				(clearance outline)
				(anchor circle)
			)
			(primitives
				(gr_poly
					(pts
						(arc
							(start 0.2159 -0.0381)
							(mid 0 -0.254)
							(end -0.2159 -0.0381)
						)
						(arc
							(start -0.2159 0.0381)
							(mid 0 0.254)
							(end 0.2159 0.0381)
						)
					)
					(width 0)
					(fill yes)
				)
			)
		)
		(pad "E22" smd custom
			(at -19.221958 -23.122128)
			(size 0.10795 0.10795)
			(layers "F.Cu" "F.Mask" "F.Paste")
			(net "GND")
			(options
				(clearance outline)
				(anchor circle)
			)
			(primitives
				(gr_poly
					(pts
						(arc
							(start 0.2159 -0.0381)
							(mid 0 -0.254)
							(end -0.2159 -0.0381)
						)
						(arc
							(start -0.2159 0.0381)
							(mid 0 0.254)
							(end 0.2159 0.0381)
						)
					)
					(width 0)
					(fill yes)
				)
			)
		)
		(pad "E24" smd custom
			(at -17.504918 -23.122128)
			(size 0.10795 0.10795)
			(layers "F.Cu" "F.Mask" "F.Paste")
			(net "TP_CPU0_RSVD_281")
			(options
				(clearance outline)
				(anchor circle)
			)
			(primitives
				(gr_poly
					(pts
						(arc
							(start 0.2159 -0.0381)
							(mid 0 -0.254)
							(end -0.2159 -0.0381)
						)
						(arc
							(start -0.2159 0.0381)
							(mid 0 0.254)
							(end 0.2159 0.0381)
						)
					)
					(width 0)
					(fill yes)
				)
			)
		)
		(pad "E26" smd circle
			(at -15.787878 -23.122128)
			(size 0.4318 0.4318)
			(layers "F.Cu" "F.Mask" "F.Paste")
			(net "M_B_DQ<51>")
		)
		(pad "E28" smd circle
			(at -14.071092 -23.122128)
			(size 0.4318 0.4318)
			(layers "F.Cu" "F.Mask" "F.Paste")
			(net "M_B_DQS_DP<6>")
		)
		(pad "E30" smd circle
			(at -12.354052 -23.122128)
			(size 0.4318 0.4318)
			(layers "F.Cu" "F.Mask" "F.Paste")
			(net "M_B_DQ<52>")
		)
		(pad "E32" smd circle
			(at -10.637012 -23.122128)
			(size 0.4318 0.4318)
			(layers "F.Cu" "F.Mask" "F.Paste")
			(net "M_B_DQ<43>")
		)
		(pad "E34" smd circle
			(at -8.919972 -23.122128)
			(size 0.4318 0.4318)
			(layers "F.Cu" "F.Mask" "F.Paste")
			(net "M_B_DQS_DP<5>")
		)
		(pad "E36" smd circle
			(at -7.202932 -23.122128)
			(size 0.4318 0.4318)
			(layers "F.Cu" "F.Mask" "F.Paste")
			(net "M_B_DQ<44>")
		)
		(pad "E38" smd circle
			(at -5.485892 -23.122128)
			(size 0.4318 0.4318)
			(layers "F.Cu" "F.Mask" "F.Paste")
			(net "M_A_DQ<35>")
		)
		(pad "E40" smd circle
			(at -3.769106 -23.122128)
			(size 0.4318 0.4318)
			(layers "F.Cu" "F.Mask" "F.Paste")
			(net "M_A_DQS_DP<4>")
		)
		(pad "E42" smd circle
			(at -2.052066 -23.122128)
			(size 0.4318 0.4318)
			(layers "F.Cu" "F.Mask" "F.Paste")
			(net "M_A_DQ<36>")
		)
		(pad "E46" smd circle
			(at 2.910586 -24.921972)
			(size 0.4318 0.4318)
			(layers "F.Cu" "F.Mask" "F.Paste")
			(net "PVDDQ_ABC")
		)
		(pad "E48" smd circle
			(at 4.627626 -24.921972)
			(size 0.4318 0.4318)
			(layers "F.Cu" "F.Mask" "F.Paste")
			(net "PVDDQ_ABC")
		)
		(pad "E50" smd circle
			(at 6.344412 -24.921972)
			(size 0.4318 0.4318)
			(layers "F.Cu" "F.Mask" "F.Paste")
			(net "PVDDQ_ABC")
		)
		(pad "E52" smd circle
			(at 8.061452 -24.921972)
			(size 0.4318 0.4318)
			(layers "F.Cu" "F.Mask" "F.Paste")
			(net "PVDDQ_ABC")
		)
		(pad "E54" smd circle
			(at 9.778492 -24.921972)
			(size 0.4318 0.4318)
			(layers "F.Cu" "F.Mask" "F.Paste")
			(net "PVDDQ_ABC")
		)
		(pad "E56" smd circle
			(at 11.495532 -24.921972)
			(size 0.4318 0.4318)
			(layers "F.Cu" "F.Mask" "F.Paste")
			(net "PVDDQ_ABC")
		)
		(pad "E58" smd circle
			(at 13.212572 -24.921972)
			(size 0.4318 0.4318)
			(layers "F.Cu" "F.Mask" "F.Paste")
			(net "PVDDQ_ABC")
		)
		(pad "E60" smd circle
			(at 14.929612 -24.921972)
			(size 0.4318 0.4318)
			(layers "F.Cu" "F.Mask" "F.Paste")
			(net "PVDDQ_ABC")
		)
		(pad "E62" smd circle
			(at 16.646398 -24.921972)
			(size 0.4318 0.4318)
			(layers "F.Cu" "F.Mask" "F.Paste")
			(net "PVDDQ_ABC")
		)
		(pad "E64" smd circle
			(at 18.363438 -24.921972)
			(size 0.4318 0.4318)
			(layers "F.Cu" "F.Mask" "F.Paste")
			(net "PVDDQ_ABC")
		)
		(pad "E66" smd custom
			(at 20.080478 -24.921972)
			(size 0.10795 0.10795)
			(layers "F.Cu" "F.Mask" "F.Paste")
			(net "GND")
			(options
				(clearance outline)
				(anchor circle)
			)
			(primitives
				(gr_poly
					(pts
						(arc
							(start 0.2159 -0.0381)
							(mid 0 -0.254)
							(end -0.2159 -0.0381)
						)
						(arc
							(start -0.2159 0.0381)
							(mid 0 0.254)
							(end 0.2159 0.0381)
						)
					)
					(width 0)
					(fill yes)
				)
			)
		)
		(pad "E72" smd circle
			(at 25.231598 -24.921972)
			(size 0.4318 0.4318)
			(layers "F.Cu" "F.Mask" "F.Paste")
			(net "GND")
		)
		(pad "E74" smd circle
			(at 26.948384 -24.921972)
			(size 0.4318 0.4318)
			(layers "F.Cu" "F.Mask" "F.Paste")
			(net "GND")
		)
		(pad "E76" smd circle
			(at 28.665424 -24.921972)
			(size 0.4318 0.4318)
			(layers "F.Cu" "F.Mask" "F.Paste")
			(net "GND")
		)
		(pad "E78" smd circle
			(at 30.382464 -24.921972)
			(size 0.4318 0.4318)
			(layers "F.Cu" "F.Mask" "F.Paste")
			(net "M_B_DQ<22>")
		)
		(pad "E80" smd circle
			(at 32.099504 -24.921972)
			(size 0.4318 0.4318)
			(layers "F.Cu" "F.Mask" "F.Paste")
			(net "M_B_DQ<16>")
		)
		(pad "E82" smd custom
			(at 33.816544 -24.921972 315)
			(size 0.10795 0.10795)
			(layers "F.Cu" "F.Mask" "F.Paste")
			(net "GND")
			(options
				(clearance outline)
				(anchor circle)
			)
			(primitives
				(gr_poly
					(pts
						(arc
							(start 0.2159 -0.0381)
							(mid 0 -0.254)
							(end -0.2159 -0.0381)
						)
						(arc
							(start -0.2159 0.0381)
							(mid 0 0.254)
							(end 0.2159 0.0381)
						)
					)
					(width 0)
					(fill yes)
				)
			)
		)
		(pad "E84" smd custom
			(at 35.533584 -24.921972 270)
			(size 0.10795 0.10795)
			(layers "F.Cu" "F.Mask" "F.Paste")
			(net "TP_CPU0_RSVD_280")
			(options
				(clearance outline)
				(anchor circle)
			)
			(primitives
				(gr_poly
					(pts
						(arc
							(start 0.2159 -0.0381)
							(mid 0 -0.254)
							(end -0.2159 -0.0381)
						)
						(arc
							(start -0.2159 0.0381)
							(mid 0 0.254)
							(end 0.2159 0.0381)
						)
					)
					(width 0)
					(fill yes)
				)
			)
		)
		(pad "EA4" smd custom
			(at -34.675064 24.426672 135)
			(size 0.10795 0.10795)
			(layers "F.Cu" "F.Mask" "F.Paste")
			(net "TP_CPU0_RSVD_20")
			(options
				(clearance outline)
				(anchor circle)
			)
			(primitives
				(gr_poly
					(pts
						(arc
							(start 0.2159 -0.0381)
							(mid 0 -0.254)
							(end -0.2159 -0.0381)
						)
						(arc
							(start -0.2159 0.0381)
							(mid 0 0.254)
							(end 0.2159 0.0381)
						)
					)
					(width 0)
					(fill yes)
				)
			)
		)
		(pad "EA6" smd circle
			(at -32.958024 24.426672)
			(size 0.4318 0.4318)
			(layers "F.Cu" "F.Mask" "F.Paste")
			(net "GND")
		)
		(pad "EA8" smd circle
			(at -31.240984 24.426672)
			(size 0.4318 0.4318)
			(layers "F.Cu" "F.Mask" "F.Paste")
			(net "P3E_CPU0_PE1_PCH_TXN<14>")
		)
		(pad "EA10" smd circle
			(at -29.523944 24.426672)
			(size 0.4318 0.4318)
			(layers "F.Cu" "F.Mask" "F.Paste")
			(net "P3E_CPU0_PE3_OCP_TXP<3>")
		)
		(pad "EA12" smd circle
			(at -27.806904 24.426672)
			(size 0.4318 0.4318)
			(layers "F.Cu" "F.Mask" "F.Paste")
			(net "PVCCIO_CPU0")
		)
		(pad "EA14" smd circle
			(at -26.090118 24.426672)
			(size 0.4318 0.4318)
			(layers "F.Cu" "F.Mask" "F.Paste")
			(net "GND")
		)
		(pad "EA16" smd custom
			(at -24.373078 24.426672 180)
			(size 0.10795 0.10795)
			(layers "F.Cu" "F.Mask" "F.Paste")
			(net "GND")
			(options
				(clearance outline)
				(anchor circle)
			)
			(primitives
				(gr_poly
					(pts
						(arc
							(start 0.2159 -0.0381)
							(mid 0 -0.254)
							(end -0.2159 -0.0381)
						)
						(arc
							(start -0.2159 0.0381)
							(mid 0 0.254)
							(end 0.2159 0.0381)
						)
					)
					(width 0)
					(fill yes)
				)
			)
		)
		(pad "EA18" smd custom
			(at -22.656038 24.426672 180)
			(size 0.10795 0.10795)
			(layers "F.Cu" "F.Mask" "F.Paste")
			(net "P3E_CPU0_PE3_OCP_RXN<0>")
			(options
				(clearance outline)
				(anchor circle)
			)
			(primitives
				(gr_poly
					(pts
						(arc
							(start 0.2159 -0.0381)
							(mid 0 -0.254)
							(end -0.2159 -0.0381)
						)
						(arc
							(start -0.2159 0.0381)
							(mid 0 0.254)
							(end 0.2159 0.0381)
						)
					)
					(width 0)
					(fill yes)
				)
			)
		)
		(pad "EA20" smd custom
			(at -20.938998 24.426672 120)
			(size 0.10795 0.10795)
			(layers "F.Cu" "F.Mask" "F.Paste")
			(net "GND")
			(options
				(clearance outline)
				(anchor circle)
			)
			(primitives
				(gr_poly
					(pts
						(arc
							(start 0.2159 -0.0381)
							(mid 0 -0.254)
							(end -0.2159 -0.0381)
						)
						(arc
							(start -0.2159 0.0381)
							(mid 0 0.254)
							(end 0.2159 0.0381)
						)
					)
					(width 0)
					(fill yes)
				)
			)
		)
		(pad "EA22" smd circle
			(at -19.221958 24.426672)
			(size 0.4318 0.4318)
			(layers "F.Cu" "F.Mask" "F.Paste")
			(net "GND")
		)
		(pad "EA24" smd circle
			(at -17.504918 24.426672)
			(size 0.4318 0.4318)
			(layers "F.Cu" "F.Mask" "F.Paste")
			(net "M_E_DQ<50>")
		)
		(pad "EA26" smd circle
			(at -15.787878 24.426672)
			(size 0.4318 0.4318)
			(layers "F.Cu" "F.Mask" "F.Paste")
			(net "M_E_DQS_DN<15>")
		)
		(pad "EA28" smd circle
			(at -14.071092 24.426672)
			(size 0.4318 0.4318)
			(layers "F.Cu" "F.Mask" "F.Paste")
			(net "M_E_DQ<53>")
		)
		(pad "EA30" smd circle
			(at -12.354052 24.426672)
			(size 0.4318 0.4318)
			(layers "F.Cu" "F.Mask" "F.Paste")
			(net "M_E_DQ<42>")
		)
	)
)
